FILE_TYPE = CONNECTIVITY;
{Allegro Design Entry HDL 17.2-2016 S081 (4005846) 1/11/2022}
"PAGE_NUMBER" = 144;
0"NC";
1"GND\g";
2"GND\g";
3"P5E_CPU0_PE3_RX_DP<9>";
4"P5E_CPU0_PE2_RX_DP<9>";
5"P5E_CPU0_PE2_RX_DN<9>";
6"P5E_CPU0_PE3_TX_C_DP<9>";
7"P5E_CPU0_PE3_RX_DN<9>";
8"PRSNT_CABLE_GPU_A1_N";
9"P5E_CPU0_PE2_TX_C_DP<9>";
10"P5E_CPU0_PE2_TX_C_DN<9>";
11"P5E_CPU0_PE3_TX_C_DN<9>";
12"PRSNT_CABLE_SWB_B1_N";
13"P5E_CPU0_PE3_RX_DP<15>";
14"P5E_CPU0_PE3_RX_DN<15>";
15"P5E_CPU0_PE2_RX_DP<15>";
16"P5E_CPU0_PE2_RX_DN<15>";
17"P5E_CPU0_PE2_TX_C_DN<15>";
18"P5E_CPU0_PE3_TX_C_DP<15>";
19"I3C_BMC_SWB_BUF_SDA";
20"P5E_CPU0_PE2_TX_C_DN<14>";
21"P5E_CPU0_PE3_TX_C_DP<14>";
22"P5E_CPU0_PE3_TX_C_DN<14>";
23"P5E_CPU0_PE2_RX_DN<14>";
24"P5E_CPU0_PE2_RX_DP<14>";
25"P5E_CPU0_PE3_TX_C_DP<13>";
26"P5E_CPU0_PE3_TX_C_DN<13>";
27"P5E_CPU0_PE2_RX_DN<13>";
28"I3C_BMC_SWB_BUF_SCL";
29"FM_SWB_PWRGD";
30"P5E_CPU0_PE3_RX_DP<13>";
31"P5E_CPU0_PE3_RX_DN<13>";
32"P5E_CPU0_PE2_RX_DP<13>";
33"P5E_CPU0_PE2_TX_C_DP<13>";
34"P5E_CPU0_PE3_RX_DN<14>";
35"P5E_CPU0_PE3_RX_DP<10>";
36"UART_BMC_BIC_TX";
37"P5E_CPU0_PE2_RX_DN<10>";
38"P5E_CPU0_PE2_TX_C_DN<8>";
39"P5E_CPU0_PE3_RX_DP<11>";
40"P5E_CPU0_PE3_RX_DN<11>";
41"UART_BMC_BIC_RX";
42"NC_J106_A5";
43"P5E_CPU0_PE3_RX_DP<14>";
44"P5E_CPU0_PE2_TX_C_DN<13>";
45"P5E_CPU0_PE2_RX_DN<11>";
46"P5E_CPU0_PE3_TX_C_DN<11>";
47"P5E_CPU0_PE2_RX_DP<11>";
48"P5E_CPU0_PE2_RX_DP<8>";
49"P5E_CPU0_PE3_RX_DP<8>";
50"P5E_CPU0_PE3_RX_DN<8>";
51"P5E_CPU0_PE2_RX_DN<8>";
52"P5E_CPU0_PE3_TX_C_DN<10>";
53"P5E_CPU0_PE3_TX_C_DP<10>";
54"P5E_CPU0_PE2_TX_C_DN<10>";
55"P5E_CPU0_PE2_TX_C_DP<10>";
56"P5E_CPU0_PE2_RX_DP<10>";
57"P5E_CPU0_PE3_RX_DN<10>";
58"P5E_CPU0_PE2_TX_C_DP<8>";
59"P5E_CPU0_PE3_TX_C_DP<8>";
60"P5E_CPU0_PE3_TX_C_DN<8>";
61"P5E_CPU0_PE2_TX_C_DP<15>";
62"P5E_CPU0_PE3_TX_C_DN<15>";
63"P5E_CPU0_PE2_TX_C_DP<14>";
64"P5E_CPU0_PE2_TX_C_DN<12>";
65"P5E_CPU0_PE2_TX_C_DP<12>";
66"P5E_CPU0_PE3_TX_C_DP<12>";
67"P5E_CPU0_PE3_TX_C_DN<12>";
68"P5E_CPU0_PE3_RX_DN<12>";
69"P5E_CPU0_PE3_RX_DP<12>";
70"P5E_CPU0_PE2_RX_DN<12>";
71"P5E_CPU0_PE2_RX_DP<12>";
72"P5E_CPU0_PE3_TX_C_DP<11>";
73"P5E_CPU0_PE2_TX_C_DN<11>";
74"P5E_CPU0_PE2_TX_C_DP<11>";
%"UNIVERSAL_GND"
"1","(-1100,2225)","0","logical_power","I17";
;
CDS_LIB"logical_power"
HDL_POWER"GND";
"A"2;
%"UNIVERSAL_GND"
"1","(3475,2100)","0","logical_power","I48";
;
HDL_POWER"GND"
CDS_LIB"logical_power";
"A"1;
%"CONN112_10137002101LF"
"2","(4625,4050)","0","pure_quanta","I65";
;
PART_NUMBER"DFHSB2FR012"
PART_TYPE"THLF"
MATERIAL"IO"
LOCATION"J106"
CDS_LMAN_SYM_OUTLINE"-775,1650,775,-1650"
NEEDS_NO_SIZE"TRUE"
CDS_LIB"pure_quanta"
VALUE"CONN112_10137002-101LF"
$SEC"2"
CDS_SEC"2";
"N4"
$PN"N4"28;
"M4"
$PN"M4"1;
"N3"
$PN"N3"1;
"M3"
$PN"M3"44;
"N2"
$PN"N2"19;
"M2"
$PN"M2"1;
"N1"
$PN"N1"1;
"M1"
$PN"M1"61;
"L1"
$PN"L1"17;
"L2"
$PN"L2"20;
"L3"
$PN"L3"33;
"L4"
$PN"L4"64;
"K1"
$PN"K1"1;
"K2"
$PN"K2"63;
"K3"
$PN"K3"1;
"K4"
$PN"K4"65;
"J1"
$PN"J1"18;
"J2"
$PN"J2"1;
"J3"
$PN"J3"25;
"J4"
$PN"J4"1;
"I1"
$PN"I1"62;
"I2"
$PN"I2"21;
"I3"
$PN"I3"26;
"I4"
$PN"I4"66;
"H1"
$PN"H1"1;
"H2"
$PN"H2"22;
"H3"
$PN"H3"1;
"H4"
$PN"H4"67;
"G1"
$PN"G1"16;
"G2"
$PN"G2"1;
"G3"
$PN"G3"27;
"G4"
$PN"G4"1;
"F1"
$PN"F1"15;
"F2"
$PN"F2"23;
"F3"
$PN"F3"32;
"F4"
$PN"F4"70;
"E1"
$PN"E1"1;
"E2"
$PN"E2"24;
"E3"
$PN"E3"1;
"E4"
$PN"E4"71;
"D1"
$PN"D1"14;
"D2"
$PN"D2"1;
"D3"
$PN"D3"31;
"D4"
$PN"D4"1;
"C1"
$PN"C1"13;
"C2"
$PN"C2"34;
"C3"
$PN"C3"30;
"C4"
$PN"C4"68;
"B1"
$PN"B1"1;
"B2"
$PN"B2"43;
"B3"
$PN"B3"1;
"B4"
$PN"B4"69;
"A1"
$PN"A1"12;
"A2"
$PN"A2"1;
"A3"
$PN"A3"29;
"A4"
$PN"A4"1;
%"CONN112_10137002101LF"
"1","(0,4125)","0","pure_quanta","I68";
;
PART_NUMBER"DFHSB2FR012"
MATERIAL"IO"
PART_TYPE"THLF"
LOCATION"J106"
CDS_LIB"pure_quanta"
NEEDS_NO_SIZE"TRUE"
CDS_LMAN_SYM_OUTLINE"-775,1650,775,-1650"
VALUE"CONN112_10137002-101LF"
$SEC"1"
CDS_SEC"1";
"N8"
$PN"N8"36;
"M8"
$PN"M8"2;
"N7"
$PN"N7"2;
"M7"
$PN"M7"10;
"N6"
$PN"N6"41;
"M6"
$PN"M6"2;
"N5"
$PN"N5"2;
"M5"
$PN"M5"73;
"L5"
$PN"L5"74;
"L6"
$PN"L6"54;
"L7"
$PN"L7"9;
"L8"
$PN"L8"38;
"K5"
$PN"K5"2;
"K6"
$PN"K6"55;
"K7"
$PN"K7"2;
"K8"
$PN"K8"58;
"J5"
$PN"J5"72;
"J6"
$PN"J6"2;
"J7"
$PN"J7"6;
"J8"
$PN"J8"2;
"I5"
$PN"I5"46;
"I6"
$PN"I6"53;
"I7"
$PN"I7"11;
"I8"
$PN"I8"59;
"H5"
$PN"H5"2;
"H6"
$PN"H6"52;
"H7"
$PN"H7"2;
"H8"
$PN"H8"60;
"G5"
$PN"G5"45;
"G6"
$PN"G6"2;
"G7"
$PN"G7"5;
"G8"
$PN"G8"2;
"F5"
$PN"F5"47;
"F6"
$PN"F6"37;
"F7"
$PN"F7"4;
"F8"
$PN"F8"51;
"E5"
$PN"E5"2;
"E6"
$PN"E6"56;
"E7"
$PN"E7"2;
"E8"
$PN"E8"48;
"D5"
$PN"D5"39;
"D6"
$PN"D6"2;
"D7"
$PN"D7"3;
"D8"
$PN"D8"2;
"C5"
$PN"C5"40;
"C6"
$PN"C6"35;
"C7"
$PN"C7"7;
"C8"
$PN"C8"49;
"B5"
$PN"B5"2;
"B6"
$PN"B6"57;
"B7"
$PN"B7"2;
"B8"
$PN"B8"50;
"A5"
$PN"A5"42;
"A6"
$PN"A6"2;
"A7"
$PN"A7"8;
"A8"
$PN"A8"2;
END.
